(kicad_pcb
	(version 20221018)
	(generator pcbnew)
	(general
    (thickness 1.518)
  )
	(paper "A4")
	(title_block
    (title "Kria K26 Devboard")
    (date "2024-03-26")
    (rev "1.2.5")
    (comment 1 "www.antmicro.com")
    (comment 2 "Antmicro Ltd.")
		(comment 9 "footprints 323-331 of 660")
	)
	(layers
    (0 "F.Cu" mixed)
    (1 "In1.Cu" power)
    (2 "In2.Cu" mixed)
    (3 "In3.Cu" power)
    (4 "In4.Cu" mixed)
    (5 "In5.Cu" power)
    (6 "In6.Cu" mixed)
    (31 "B.Cu" power)
    (32 "B.Adhes" user "B.Adhesive")
    (33 "F.Adhes" user "F.Adhesive")
    (34 "B.Paste" user)
    (35 "F.Paste" user)
    (36 "B.SilkS" user "B.Silkscreen")
    (37 "F.SilkS" user "F.Silkscreen")
    (38 "B.Mask" user)
    (39 "F.Mask" user)
    (40 "Dwgs.User" user "User.Drawings")
    (41 "Cmts.User" user "User.Comments")
    (42 "Eco1.User" user "User.Eco1")
    (43 "Eco2.User" user "User.Eco2")
    (44 "Edge.Cuts" user)
    (45 "Margin" user)
    (46 "B.CrtYd" user "B.Courtyard")
    (47 "F.CrtYd" user "F.Courtyard")
    (48 "B.Fab" user)
    (49 "F.Fab" user)
  )
	(footprint "kria-k26-devboard-footprints:R_0402_1005Metric" (layer "F.Cu")
    (at 176.275 126.975)
    (descr "Resistor SMD 0402")
    (tags "resistor SMD 0402")
    (property "Author" "Antmicro")
    (property "License" "Apache-2.0")
    (property "MPN" "CR0402-FX-2402GLF")
    (property "Manufacturer" "Bourns")
    (property "Sheetfile" "dc-dc-conventers.kicad_sch")
    (property "Sheetname" "DC/DC conventers")
    (property "Tolerance" "1%")
    (property "Val" "24k")
    (property "ki_description" "24k resistor in 0402 package with 1% tolerance")
    (attr smd)
    (fp_text reference "R125" (at -1.345 3.035) (layer "F.SilkS")
        (effects (font (size 0.7 0.7) (thickness 0.15)) (justify left bottom))
    )
    (fp_text value "R_24k_0402" (at 0 1.4) (layer "F.Fab") hide
        (effects (font (size 0.7 0.7) (thickness 0.15)) (justify left bottom))
    )
    (fp_text user "License: Apache-2.0" (at -0.95 5.169) (layer "F.Fab") hide
        (effects (font (size 0.7 0.7) (thickness 0.15)) (justify left bottom))
    )
    (fp_text user "Author: Antmicro" (at -0.95 4.169) (layer "F.Fab") hide
        (effects (font (size 0.7 0.7) (thickness 0.15)) (justify left bottom))
    )
    (fp_text user "${REFERENCE}" (at -0.95 3.168) (layer "F.Fab") hide
        (effects (font (size 0.7 0.7) (thickness 0.15)) (justify left bottom))
    )
    (fp_rect (start -0.93 -0.47) (end 0.93 0.47)
      (stroke (width 0.05) (type solid)) (fill none) (layer "F.CrtYd"))
    (fp_rect (start -0.5 -0.25) (end 0.5 0.25)
      (stroke (width 0.15) (type solid)) (fill none) (layer "F.Fab"))
    (pad "1" smd roundrect (at -0.485 0) (size 0.59 0.64) (layers "F.Cu" "F.Paste" "F.Mask") (roundrect_rratio 0.25)
      (net 255 "Net-(U48-FB)") (pintype "passive"))
    (pad "2" smd roundrect (at 0.485 0) (size 0.59 0.64) (layers "F.Cu" "F.Paste" "F.Mask") (roundrect_rratio 0.25)
      (net 1 "GND") (pintype "passive"))
  )
	(footprint "kria-k26-devboard-footprints:C_0402_1005Metric" (layer "F.Cu")
    (at 176.275 125.025)
    (descr "Capacitor SMD 0402")
    (tags "capacitor SMD 0402")
    (property "Author" "Antmicro")
    (property "Dielectric" "")
    (property "License" "Apache-2.0")
    (property "MPN" "C1005X6S1A105K050BC")
    (property "Manufacturer" "TDK")
    (property "Sheetfile" "dc-dc-conventers.kicad_sch")
    (property "Sheetname" "DC/DC conventers")
    (property "Val" "1u")
    (property "Voltage" "")
    (property "ki_description" " ")
    (attr smd)
    (fp_text reference "C188" (at -1.185 3.175) (layer "F.SilkS")
        (effects (font (size 0.7 0.7) (thickness 0.15)) (justify left bottom))
    )
    (fp_text value "C_1u_0402" (at 0 1.4) (layer "F.Fab") hide
        (effects (font (size 0.7 0.7) (thickness 0.15)) (justify left bottom))
    )
    (fp_text user "License: Apache-2.0" (at -0.932 5.17) (layer "F.Fab") hide
        (effects (font (size 0.7 0.7) (thickness 0.15)) (justify left bottom))
    )
    (fp_text user "${REFERENCE}" (at -0.932 3.168) (layer "F.Fab") hide
        (effects (font (size 0.7 0.7) (thickness 0.15)) (justify left bottom))
    )
    (fp_text user "Author: Antmicro" (at -0.932 4.17) (layer "F.Fab") hide
        (effects (font (size 0.7 0.7) (thickness 0.15)) (justify left bottom))
    )
    (fp_rect (start -0.94 -0.47) (end 0.94 0.47)
      (stroke (width 0.05) (type solid)) (fill none) (layer "F.CrtYd"))
    (fp_rect (start -0.499 -0.249) (end 0.499 0.249)
      (stroke (width 0.15) (type solid)) (fill none) (layer "F.Fab"))
    (pad "1" smd roundrect (at -0.484 0) (size 0.59 0.64) (layers "F.Cu" "F.Paste" "F.Mask") (roundrect_rratio 0.25)
      (net 249 "Net-(U48-PVCC)") (pintype "passive"))
    (pad "2" smd roundrect (at 0.484 0) (size 0.59 0.64) (layers "F.Cu" "F.Paste" "F.Mask") (roundrect_rratio 0.25)
      (net 1 "GND") (pintype "passive"))
  )
	(footprint "kria-k26-devboard-footprints:C_0603_1608Metric" (layer "F.Cu")
    (at 177.46 123.22 -90)
    (descr "Capacitor SMD 0603")
    (tags "capacitor 0603")
    (property "Author" "Antmicro")
    (property "Dielectric" "")
    (property "License" "Apache-2.0")
    (property "MPN" "C1608X5R1E106M080AC")
    (property "Manufacturer" "TDK")
    (property "Sheetfile" "dc-dc-conventers.kicad_sch")
    (property "Sheetname" "DC/DC conventers")
    (property "Val" "10u/25V")
    (property "Voltage" "")
    (property "ki_description" " ")
    (attr smd)
    (fp_text reference "C186" (at 3.655 -2.09 -90) (layer "F.SilkS")
        (effects (font (size 0.7 0.7) (thickness 0.15)) (justify left bottom))
    )
    (fp_text value "C_10u_25V_0603" (at 0 1.6 -90) (layer "F.Fab") hide
        (effects (font (size 0.7 0.7) (thickness 0.15)) (justify left bottom))
    )
    (fp_text user "${REFERENCE}" (at -1.682 3.895 -90) (layer "F.Fab") hide
        (effects (font (size 0.7 0.7) (thickness 0.15)) (justify left bottom))
    )
    (fp_text user "Author: Antmicro" (at -1.682 4.894 -90) (layer "F.Fab") hide
        (effects (font (size 0.7 0.7) (thickness 0.15)) (justify left bottom))
    )
    (fp_text user "License: Apache-2.0" (at -1.682 5.895 -90) (layer "F.Fab") hide
        (effects (font (size 0.7 0.7) (thickness 0.15)) (justify left bottom))
    )
    (fp_line (start -0.3 -0.3) (end 0.3 -0.3)
      (stroke (width 0.15) (type solid)) (layer "F.SilkS"))
    (fp_line (start -0.3 0.3) (end 0.3 0.3)
      (stroke (width 0.15) (type solid)) (layer "F.SilkS"))
    (fp_rect (start -1.24 -0.7) (end 1.24 0.7)
      (stroke (width 0.05) (type solid)) (fill none) (layer "F.CrtYd"))
    (fp_rect (start -0.8 -0.4) (end 0.8 0.4)
      (stroke (width 0.15) (type solid)) (fill none) (layer "F.Fab"))
    (pad "1" smd roundrect (at -0.7 0 270) (size 0.6 0.8) (layers "F.Cu" "F.Paste" "F.Mask") (roundrect_rratio 0.2)
      (net 14 "/Power Supply/DC/DC conventers/DC_MAIN_BUS") (pintype "passive"))
    (pad "2" smd roundrect (at 0.7 0 270) (size 0.6 0.8) (layers "F.Cu" "F.Paste" "F.Mask") (roundrect_rratio 0.2)
      (net 1 "GND") (pintype "passive"))
  )
	(footprint "kria-k26-devboard-footprints:C_0402_1005Metric" (layer "F.Cu")
    (at 171.35 122.85 180)
    (descr "Capacitor SMD 0402")
    (tags "capacitor SMD 0402")
    (property "Author" "Antmicro")
    (property "Dielectric" "X5R")
    (property "License" "Apache-2.0")
    (property "MPN" "GRM155R61H104KE14D")
    (property "Manufacturer" "Murata")
    (property "Sheetfile" "dc-dc-conventers.kicad_sch")
    (property "Sheetname" "DC/DC conventers")
    (property "Val" "100n")
    (property "Voltage" "50V")
    (property "ki_description" " ")
    (attr smd)
    (fp_text reference "C192" (at 0.62 0.48) (layer "F.SilkS")
        (effects (font (size 0.7 0.7) (thickness 0.15)) (justify left bottom))
    )
    (fp_text value "C_100n_0402" (at 0 1.4 180) (layer "F.Fab") hide
        (effects (font (size 0.7 0.7) (thickness 0.15)) (justify left bottom))
    )
    (fp_text user "${REFERENCE}" (at -0.932 3.168 180) (layer "F.Fab") hide
        (effects (font (size 0.7 0.7) (thickness 0.15)) (justify left bottom))
    )
    (fp_text user "Author: Antmicro" (at -0.932 4.17 180) (layer "F.Fab") hide
        (effects (font (size 0.7 0.7) (thickness 0.15)) (justify left bottom))
    )
    (fp_text user "License: Apache-2.0" (at -0.932 5.17 180) (layer "F.Fab") hide
        (effects (font (size 0.7 0.7) (thickness 0.15)) (justify left bottom))
    )
    (fp_rect (start -0.94 -0.47) (end 0.94 0.47)
      (stroke (width 0.05) (type solid)) (fill none) (layer "F.CrtYd"))
    (fp_rect (start -0.499 -0.249) (end 0.499 0.249)
      (stroke (width 0.15) (type solid)) (fill none) (layer "F.Fab"))
    (pad "1" smd roundrect (at -0.484 0 180) (size 0.59 0.64) (layers "F.Cu" "F.Paste" "F.Mask") (roundrect_rratio 0.25)
      (net 253 "Net-(U48-BOOT)") (pintype "passive"))
    (pad "2" smd roundrect (at 0.484 0 180) (size 0.59 0.64) (layers "F.Cu" "F.Paste" "F.Mask") (roundrect_rratio 0.25)
      (net 366 "/Power Supply/DC/DC conventers/SW_SOM_5V") (pintype "passive"))
  )
	(footprint "kria-k26-devboard-footprints:L_Coilcraft-XEL4030" (layer "F.Cu")
    (at 168.2 124.675 180)
    (property "Author" "Antmicro")
    (property "IMax" "")
    (property "ISat" "")
    (property "License" "Apache-2.0")
    (property "MPN" "XEL4030-332MEC")
    (property "Manufacturer" "Coilcraft")
    (property "Sheetfile" "dc-dc-conventers.kicad_sch")
    (property "Sheetname" "DC/DC conventers")
    (property "Size" "4x4")
    (property "Val" "3u3/5.9A")
    (attr smd)
    (fp_text reference "L2" (at 3.54 1.295 180) (layer "F.SilkS")
        (effects (font (size 0.7 0.7) (thickness 0.15)) (justify left bottom))
    )
    (fp_text value "L_3u3_5.9A_XEL4030" (at 0.05 2.996 180) (layer "F.Fab") hide
        (effects (font (size 0.7 0.7) (thickness 0.15)) (justify left bottom))
    )
    (fp_text user "Author: Antmicro" (at -2.15 5.996 180) (layer "F.Fab") hide
        (effects (font (size 0.7 0.7) (thickness 0.15)) (justify left bottom))
    )
    (fp_text user "${REFERENCE}" (at -2.15 4.996 180) (layer "F.Fab") hide
        (effects (font (size 0.7 0.7) (thickness 0.15)) (justify left bottom))
    )
    (fp_text user "License: Apache-2.0" (at -2.15 6.996 180) (layer "F.Fab") hide
        (effects (font (size 0.7 0.7) (thickness 0.15)) (justify left bottom))
    )
    (fp_line (start -1.8 -2.2) (end 1.85 -2.201)
      (stroke (width 0.15) (type solid)) (layer "F.SilkS"))
    (fp_line (start -1.8 2.2) (end 1.85 2.199)
      (stroke (width 0.15) (type solid)) (layer "F.SilkS"))
    (fp_rect (start -2.45 -2.45) (end 2.45 2.45)
      (stroke (width 0.05) (type solid)) (fill none) (layer "F.CrtYd"))
    (fp_line (start -2 -2) (end 1.999 -2)
      (stroke (width 0.15) (type solid)) (layer "F.Fab"))
    (fp_line (start -2 1.999) (end -2 -2)
      (stroke (width 0.15) (type solid)) (layer "F.Fab"))
    (fp_line (start 1.999 -2) (end 1.999 1.999)
      (stroke (width 0.15) (type solid)) (layer "F.Fab"))
    (fp_line (start 1.999 1.999) (end -2 1.999)
      (stroke (width 0.15) (type solid)) (layer "F.Fab"))
    (pad "1" smd rect (at -1.186 0 180) (size 0.98 3.4) (layers "F.Cu" "F.Paste" "F.Mask")
      (net 366 "/Power Supply/DC/DC conventers/SW_SOM_5V") (pintype "passive"))
    (pad "2" smd rect (at 1.185 0 180) (size 0.98 3.4) (layers "F.Cu" "F.Paste" "F.Mask")
      (net 773 "/Power Supply/DC/DC conventers/SOM_5V_OUT") (pintype "passive"))
  )
	(footprint "kria-k26-devboard-footprints:C_0603_1608Metric" (layer "F.Cu")
    (at 176.049999 123.225 -90)
    (descr "Capacitor SMD 0603")
    (tags "capacitor 0603")
    (property "Author" "Antmicro")
    (property "Dielectric" "")
    (property "License" "Apache-2.0")
    (property "MPN" "C1608X5R1E106M080AC")
    (property "Manufacturer" "TDK")
    (property "Sheetfile" "dc-dc-conventers.kicad_sch")
    (property "Sheetname" "DC/DC conventers")
    (property "Val" "10u/25V")
    (property "Voltage" "")
    (property "ki_description" " ")
    (attr smd)
    (fp_text reference "C184" (at 3.665 -2.480001 -90) (layer "F.SilkS")
        (effects (font (size 0.7 0.7) (thickness 0.15)) (justify left bottom))
    )
    (fp_text value "C_10u_25V_0603" (at 0 1.6 -90) (layer "F.Fab") hide
        (effects (font (size 0.7 0.7) (thickness 0.15)) (justify left bottom))
    )
    (fp_text user "Author: Antmicro" (at -1.682 4.894 -90) (layer "F.Fab") hide
        (effects (font (size 0.7 0.7) (thickness 0.15)) (justify left bottom))
    )
    (fp_text user "${REFERENCE}" (at -1.682 3.895 -90) (layer "F.Fab") hide
        (effects (font (size 0.7 0.7) (thickness 0.15)) (justify left bottom))
    )
    (fp_text user "License: Apache-2.0" (at -1.682 5.895 -90) (layer "F.Fab") hide
        (effects (font (size 0.7 0.7) (thickness 0.15)) (justify left bottom))
    )
    (fp_line (start -0.3 -0.3) (end 0.3 -0.3)
      (stroke (width 0.15) (type solid)) (layer "F.SilkS"))
    (fp_line (start -0.3 0.3) (end 0.3 0.3)
      (stroke (width 0.15) (type solid)) (layer "F.SilkS"))
    (fp_rect (start -1.24 -0.7) (end 1.24 0.7)
      (stroke (width 0.05) (type solid)) (fill none) (layer "F.CrtYd"))
    (fp_rect (start -0.8 -0.4) (end 0.8 0.4)
      (stroke (width 0.15) (type solid)) (fill none) (layer "F.Fab"))
    (pad "1" smd roundrect (at -0.7 0 270) (size 0.6 0.8) (layers "F.Cu" "F.Paste" "F.Mask") (roundrect_rratio 0.2)
      (net 14 "/Power Supply/DC/DC conventers/DC_MAIN_BUS") (pintype "passive"))
    (pad "2" smd roundrect (at 0.7 0 270) (size 0.6 0.8) (layers "F.Cu" "F.Paste" "F.Mask") (roundrect_rratio 0.2)
      (net 1 "GND") (pintype "passive"))
  )
	(footprint "kria-k26-devboard-footprints:C_0402_1005Metric" (layer "F.Cu")
    (at 176.15 135.825 -90)
    (descr "Capacitor SMD 0402")
    (tags "capacitor SMD 0402")
    (property "Author" "Antmicro")
    (property "Dielectric" "X5R")
    (property "License" "Apache-2.0")
    (property "MPN" "GRM155R61H104KE14D")
    (property "Manufacturer" "Murata")
    (property "Sheetfile" "dc-dc-conventers.kicad_sch")
    (property "Sheetname" "DC/DC conventers")
    (property "Val" "100n")
    (property "Voltage" "50V")
    (property "ki_description" " ")
    (attr smd)
    (fp_text reference "C221" (at 1.625 0.49 -90) (layer "F.SilkS")
        (effects (font (size 0.7 0.7) (thickness 0.15)) (justify left bottom))
    )
    (fp_text value "C_100n_0402" (at 0 1.4 -90) (layer "F.Fab") hide
        (effects (font (size 0.7 0.7) (thickness 0.15)) (justify left bottom))
    )
    (fp_text user "Author: Antmicro" (at -0.932 4.17 -90) (layer "F.Fab") hide
        (effects (font (size 0.7 0.7) (thickness 0.15)) (justify left bottom))
    )
    (fp_text user "${REFERENCE}" (at -0.932 3.168 -90) (layer "F.Fab") hide
        (effects (font (size 0.7 0.7) (thickness 0.15)) (justify left bottom))
    )
    (fp_text user "License: Apache-2.0" (at -0.932 5.17 -90) (layer "F.Fab") hide
        (effects (font (size 0.7 0.7) (thickness 0.15)) (justify left bottom))
    )
    (fp_rect (start -0.94 -0.47) (end 0.94 0.47)
      (stroke (width 0.05) (type solid)) (fill none) (layer "F.CrtYd"))
    (fp_rect (start -0.499 -0.249) (end 0.499 0.249)
      (stroke (width 0.15) (type solid)) (fill none) (layer "F.Fab"))
    (pad "1" smd roundrect (at -0.484 0 270) (size 0.59 0.64) (layers "F.Cu" "F.Paste" "F.Mask") (roundrect_rratio 0.25)
      (net 325 "Net-(U54-BST)") (pintype "passive"))
    (pad "2" smd roundrect (at 0.484 0 270) (size 0.59 0.64) (layers "F.Cu" "F.Paste" "F.Mask") (roundrect_rratio 0.25)
      (net 315 "/Power Supply/DC/DC conventers/SW_PL_3V3") (pintype "passive"))
  )
	(footprint "kria-k26-devboard-footprints:C_0402_1005Metric" (layer "F.Cu")
    (at 189.4 123 -90)
    (descr "Capacitor SMD 0402")
    (tags "capacitor SMD 0402")
    (property "Author" "Antmicro")
    (property "Dielectric" "X5R")
    (property "License" "Apache-2.0")
    (property "MPN" "GRM155R61H104KE14D")
    (property "Manufacturer" "Murata")
    (property "Sheetfile" "supply-oring.kicad_sch")
    (property "Sheetname" "Supply ORing")
    (property "Val" "100n")
    (property "Voltage" "50V")
    (property "ki_description" " ")
    (attr smd)
    (fp_text reference "C228" (at 3.73 -0.36 -90) (layer "F.SilkS")
        (effects (font (size 0.7 0.7) (thickness 0.15)) (justify left bottom))
    )
    (fp_text value "C_100n_0402" (at 0 1.4 -90) (layer "F.Fab") hide
        (effects (font (size 0.7 0.7) (thickness 0.15)) (justify left bottom))
    )
    (fp_text user "Author: Antmicro" (at -0.932 4.17 -90) (layer "F.Fab") hide
        (effects (font (size 0.7 0.7) (thickness 0.15)) (justify left bottom))
    )
    (fp_text user "${REFERENCE}" (at -0.932 3.168 -90) (layer "F.Fab") hide
        (effects (font (size 0.7 0.7) (thickness 0.15)) (justify left bottom))
    )
    (fp_text user "License: Apache-2.0" (at -0.932 5.17 -90) (layer "F.Fab") hide
        (effects (font (size 0.7 0.7) (thickness 0.15)) (justify left bottom))
    )
    (fp_rect (start -0.94 -0.47) (end 0.94 0.47)
      (stroke (width 0.05) (type solid)) (fill none) (layer "F.CrtYd"))
    (fp_rect (start -0.499 -0.249) (end 0.499 0.249)
      (stroke (width 0.15) (type solid)) (fill none) (layer "F.Fab"))
    (pad "1" smd roundrect (at -0.484 0 270) (size 0.59 0.64) (layers "F.Cu" "F.Paste" "F.Mask") (roundrect_rratio 0.25)
      (net 14 "/Power Supply/DC/DC conventers/DC_MAIN_BUS") (pintype "passive"))
    (pad "2" smd roundrect (at 0.484 0 270) (size 0.59 0.64) (layers "F.Cu" "F.Paste" "F.Mask") (roundrect_rratio 0.25)
      (net 1 "GND") (pintype "passive"))
  )
	(footprint "kria-k26-devboard-footprints:C_0603_1608Metric" (layer "F.Cu")
    (at 169.65 128.589999 -90)
    (descr "Capacitor SMD 0603")
    (tags "capacitor 0603")
    (property "Author" "Antmicro")
    (property "Dielectric" "")
    (property "License" "Apache-2.0")
    (property "MPN" "CL10A226MO7JZNC")
    (property "Manufacturer" "Samsung")
    (property "Sheetfile" "dc-dc-conventers.kicad_sch")
    (property "Sheetname" "DC/DC conventers")
    (property "Val" "22u/16V")
    (property "Voltage" "")
    (property "ki_description" " ")
    (attr smd)
    (fp_text reference "C196" (at -1.555 4.41 -90) (layer "F.SilkS")
        (effects (font (size 0.7 0.7) (thickness 0.15)) (justify left bottom))
    )
    (fp_text value "C_22u_16V_0603" (at 0 1.6 -90) (layer "F.Fab") hide
        (effects (font (size 0.7 0.7) (thickness 0.15)) (justify left bottom))
    )
    (fp_text user "Author: Antmicro" (at -1.682 4.894 -90) (layer "F.Fab") hide
        (effects (font (size 0.7 0.7) (thickness 0.15)) (justify left bottom))
    )
    (fp_text user "${REFERENCE}" (at -1.682 3.895 -90) (layer "F.Fab") hide
        (effects (font (size 0.7 0.7) (thickness 0.15)) (justify left bottom))
    )
    (fp_text user "License: Apache-2.0" (at -1.682 5.895 -90) (layer "F.Fab") hide
        (effects (font (size 0.7 0.7) (thickness 0.15)) (justify left bottom))
    )
    (fp_line (start -0.3 -0.3) (end 0.3 -0.3)
      (stroke (width 0.15) (type solid)) (layer "F.SilkS"))
    (fp_line (start -0.3 0.3) (end 0.3 0.3)
      (stroke (width 0.15) (type solid)) (layer "F.SilkS"))
    (fp_rect (start -1.24 -0.7) (end 1.24 0.7)
      (stroke (width 0.05) (type solid)) (fill none) (layer "F.CrtYd"))
    (fp_rect (start -0.8 -0.4) (end 0.8 0.4)
      (stroke (width 0.15) (type solid)) (fill none) (layer "F.Fab"))
    (pad "1" smd roundrect (at -0.7 0 270) (size 0.6 0.8) (layers "F.Cu" "F.Paste" "F.Mask") (roundrect_rratio 0.2)
      (net 773 "/Power Supply/DC/DC conventers/SOM_5V_OUT") (pintype "passive"))
    (pad "2" smd roundrect (at 0.7 0 270) (size 0.6 0.8) (layers "F.Cu" "F.Paste" "F.Mask") (roundrect_rratio 0.2)
      (net 1 "GND") (pintype "passive"))
  )
)
